FILE_TYPE=LIBRARY_PARTS;
primitive '82K5R2F-GP_SMD-RG';
  pin
    '1':
      PIN_NUMBER='(1)';
      PIN_TYPE='ANALOG';
      NO_LOAD_CHECK='Both';
      NO_IO_CHECK='Both';
      NO_ASSERT_CHECK='TRUE';
      NO_DIR_CHECK='TRUE';
      ALLOW_CONNECT='TRUE';
    '2':
      PIN_NUMBER='(2)';
      PIN_TYPE='ANALOG';
      NO_LOAD_CHECK='Both';
      NO_IO_CHECK='Both';
      NO_ASSERT_CHECK='TRUE';
      NO_DIR_CHECK='TRUE';
      ALLOW_CONNECT='TRUE';
  end_pin;
  body
    PART_NAME='82K5R2F-GP';
    BODY_NAME='82K5R2F-GP';
    PHYS_DES_PREFIX='R';
    CLASS='DISCRETE';
  end_body;
end_primitive;

END.
